(kicad_pcb
	(version 20260206)
	(generator "pcbnew")
	(generator_version "10.0")
	(general
		(thickness 1.6)
		(legacy_teardrops no)
	)
	(paper "A4")
	(title_block
		(title "baseboard — 13948-1b.1110WZS1818.brd")
		(comment 1 "Honey Badger (Wiwynn) / footprints 2019-2026 of 2523")
	)
	(layers
		(0 "F.Cu" signal "TOP")
		(4 "In1.Cu" signal "L2GND")
		(6 "In2.Cu" signal "L3")
		(8 "In3.Cu" signal "L4VCC")
		(10 "In4.Cu" signal "L5VCC")
		(12 "In5.Cu" signal "L6")
		(14 "In6.Cu" signal "L7GND")
		(2 "B.Cu" signal "BOTTOM")
		(9 "F.Adhes" user "F.Adhesive")
		(11 "B.Adhes" user "B.Adhesive")
		(13 "F.Paste" user "Package Geometry/Pastemask Top")
		(15 "B.Paste" user "Package Geometry/Pastemask Bottom")
		(5 "F.SilkS" user "Ref Des/Silkscreen Top")
		(7 "B.SilkS" user "Ref Des/Silkscreen Bottom")
		(1 "F.Mask" user "Board Geometry/Soldermask Top")
		(3 "B.Mask" user "Board Geometry/Soldermask Bottom")
		(17 "Dwgs.User" user "User.Drawings")
		(19 "Cmts.User" user "User.Comments")
		(21 "Eco1.User" user "User.Eco1")
		(23 "Eco2.User" user "User.Eco2")
		(25 "Edge.Cuts" user "Board Geometry/Outline")
		(27 "Margin" user)
		(31 "F.CrtYd" user "Package Geometry/Place Bound Top")
		(29 "B.CrtYd" user "Package Geometry/Place Bound Bottom")
		(35 "F.Fab" user "Ref Des/Assembly Top")
		(33 "B.Fab" user "Ref Des/Assembly Bottom")
	)
	(footprint ""
		(layer "B.Cu")
		(at 98.679 -50.9524 -90)
		(property "Reference" "SC1043"
			(at 0 0 90)
			(layer "B.SilkS")
			(hide yes)
			(effects
				(font
					(size 1.27 1.27)
				)
				(justify mirror)
			)
		)
		(property "Value" "SCD1U16V2KX-3GP"
			(at -1.1811 -2.7051 270)
			(unlocked yes)
			(layer "B.Fab")
			(hide yes)
			(effects
				(font
					(size 1.016 1.016)
					(thickness 0.1524)
				)
				(justify mirror)
			)
		)
		(property "Device Type" "C402H22"
			(at -1.1811 -4.2291 270)
			(unlocked yes)
			(layer "B.Fab")
			(hide yes)
			(effects
				(font
					(size 1.016 1.016)
					(thickness 0.1524)
				)
				(justify mirror)
			)
		)
		(duplicate_pad_numbers_are_jumpers no)
		(fp_rect
			(start 0.4318 0.9525)
			(end -0.4318 -0.9525)
			(stroke
				(width 0)
				(type default)
			)
			(fill no)
			(layer "B.CrtYd")
		)
		(fp_rect
			(start 0.4318 0.9525)
			(end -0.4318 -0.9525)
			(stroke
				(width 0)
				(type default)
			)
			(fill no)
			(layer "B.Fab")
		)
		(pad "1" smd custom
			(at 0 -0.4445 90)
			(size 0.1524 0.1524)
			(layers "B.Cu" "B.Mask" "B.Paste")
			(net "P0V955_C")
			(options
				(clearance outline)
				(anchor circle)
			)
			(primitives
				(gr_poly
					(pts
						(arc
							(start 0.3048 0.2032)
							(mid 0.275042 0.275042)
							(end 0.2032 0.3048)
						)
						(arc
							(start -0.2032 0.3048)
							(mid -0.275042 0.275042)
							(end -0.3048 0.2032)
						)
						(arc
							(start -0.3048 -0.2032)
							(mid -0.275042 -0.275042)
							(end -0.2032 -0.3048)
						)
						(arc
							(start 0.2032 -0.3048)
							(mid 0.275042 -0.275042)
							(end 0.3048 -0.2032)
						)
					)
					(width 0)
					(fill yes)
				)
			)
		)
		(pad "2" smd custom
			(at 0 0.4445 90)
			(size 0.1524 0.1524)
			(layers "B.Cu" "B.Mask" "B.Paste")
			(net "GND")
			(options
				(clearance outline)
				(anchor circle)
			)
			(primitives
				(gr_poly
					(pts
						(arc
							(start 0.3048 0.2032)
							(mid 0.275042 0.275042)
							(end 0.2032 0.3048)
						)
						(arc
							(start -0.2032 0.3048)
							(mid -0.275042 0.275042)
							(end -0.3048 0.2032)
						)
						(arc
							(start -0.3048 -0.2032)
							(mid -0.275042 -0.275042)
							(end -0.2032 -0.3048)
						)
						(arc
							(start 0.2032 -0.3048)
							(mid 0.275042 -0.275042)
							(end 0.3048 -0.2032)
						)
					)
					(width 0)
					(fill yes)
				)
			)
		)
	)
	(footprint ""
		(layer "B.Cu")
		(at 102.235 -37.719 90)
		(property "Reference" "SC950"
			(at 0 0 90)
			(layer "B.SilkS")
			(hide yes)
			(effects
				(font
					(size 1.27 1.27)
				)
				(justify mirror)
			)
		)
		(property "Value" "SCD1U6D3V1KX-GP"
			(at 2.8321 -1.7399 90)
			(unlocked yes)
			(layer "B.Fab")
			(hide yes)
			(effects
				(font
					(size 1.016 1.016)
					(thickness 0.1524)
				)
				(justify mirror)
			)
		)
		(property "Device Type" "C0201H13"
			(at 2.8321 -3.2639 90)
			(unlocked yes)
			(layer "B.Fab")
			(hide yes)
			(effects
				(font
					(size 1.016 1.016)
					(thickness 0.1524)
				)
				(justify mirror)
			)
		)
		(duplicate_pad_numbers_are_jumpers no)
		(fp_rect
			(start 0.2794 0.6477)
			(end -0.2794 -0.6477)
			(stroke
				(width 0)
				(type default)
			)
			(fill no)
			(layer "B.CrtYd")
		)
		(fp_rect
			(start 0.2794 0.6477)
			(end -0.2794 -0.6477)
			(stroke
				(width 0)
				(type default)
			)
			(fill no)
			(layer "B.Fab")
		)
		(pad "1" smd custom
			(at 0 -0.2794 270)
			(size 0.0762 0.0762)
			(layers "B.Cu" "B.Mask" "B.Paste")
			(net "PCE_AVDD")
			(options
				(clearance outline)
				(anchor circle)
			)
			(primitives
				(gr_poly
					(pts
						(arc
							(start 0.1524 0.127)
							(mid 0.137521 0.162921)
							(end 0.1016 0.1778)
						)
						(arc
							(start -0.1016 0.1778)
							(mid -0.137521 0.162921)
							(end -0.1524 0.127)
						)
						(arc
							(start -0.1524 -0.127)
							(mid -0.137521 -0.162921)
							(end -0.1016 -0.1778)
						)
						(arc
							(start 0.1016 -0.1778)
							(mid 0.137521 -0.162921)
							(end 0.1524 -0.127)
						)
					)
					(width 0)
					(fill yes)
				)
			)
		)
		(pad "2" smd custom
			(at 0 0.2794 270)
			(size 0.0762 0.0762)
			(layers "B.Cu" "B.Mask" "B.Paste")
			(net "GND")
			(options
				(clearance outline)
				(anchor circle)
			)
			(primitives
				(gr_poly
					(pts
						(arc
							(start 0.1524 0.127)
							(mid 0.137521 0.162921)
							(end 0.1016 0.1778)
						)
						(arc
							(start -0.1016 0.1778)
							(mid -0.137521 0.162921)
							(end -0.1524 0.127)
						)
						(arc
							(start -0.1524 -0.127)
							(mid -0.137521 -0.162921)
							(end -0.1016 -0.1778)
						)
						(arc
							(start 0.1016 -0.1778)
							(mid 0.137521 -0.162921)
							(end 0.1524 -0.127)
						)
					)
					(width 0)
					(fill yes)
				)
			)
		)
	)
	(footprint ""
		(layer "B.Cu")
		(at 97.663 -37.973 90)
		(property "Reference" "SC949"
			(at 0 0 90)
			(layer "B.SilkS")
			(hide yes)
			(effects
				(font
					(size 1.27 1.27)
				)
				(justify mirror)
			)
		)
		(property "Value" "SCD1U6D3V1KX-GP"
			(at 2.8321 -1.7399 90)
			(unlocked yes)
			(layer "B.Fab")
			(hide yes)
			(effects
				(font
					(size 1.016 1.016)
					(thickness 0.1524)
				)
				(justify mirror)
			)
		)
		(property "Device Type" "C0201H13"
			(at 2.8321 -3.2639 90)
			(unlocked yes)
			(layer "B.Fab")
			(hide yes)
			(effects
				(font
					(size 1.016 1.016)
					(thickness 0.1524)
				)
				(justify mirror)
			)
		)
		(duplicate_pad_numbers_are_jumpers no)
		(fp_rect
			(start 0.2794 0.6477)
			(end -0.2794 -0.6477)
			(stroke
				(width 0)
				(type default)
			)
			(fill no)
			(layer "B.CrtYd")
		)
		(fp_rect
			(start 0.2794 0.6477)
			(end -0.2794 -0.6477)
			(stroke
				(width 0)
				(type default)
			)
			(fill no)
			(layer "B.Fab")
		)
		(pad "1" smd custom
			(at 0 -0.2794 270)
			(size 0.0762 0.0762)
			(layers "B.Cu" "B.Mask" "B.Paste")
			(net "PCE_AVDD")
			(options
				(clearance outline)
				(anchor circle)
			)
			(primitives
				(gr_poly
					(pts
						(arc
							(start 0.1524 0.127)
							(mid 0.137521 0.162921)
							(end 0.1016 0.1778)
						)
						(arc
							(start -0.1016 0.1778)
							(mid -0.137521 0.162921)
							(end -0.1524 0.127)
						)
						(arc
							(start -0.1524 -0.127)
							(mid -0.137521 -0.162921)
							(end -0.1016 -0.1778)
						)
						(arc
							(start 0.1016 -0.1778)
							(mid 0.137521 -0.162921)
							(end 0.1524 -0.127)
						)
					)
					(width 0)
					(fill yes)
				)
			)
		)
		(pad "2" smd custom
			(at 0 0.2794 270)
			(size 0.0762 0.0762)
			(layers "B.Cu" "B.Mask" "B.Paste")
			(net "GND")
			(options
				(clearance outline)
				(anchor circle)
			)
			(primitives
				(gr_poly
					(pts
						(arc
							(start 0.1524 0.127)
							(mid 0.137521 0.162921)
							(end 0.1016 0.1778)
						)
						(arc
							(start -0.1016 0.1778)
							(mid -0.137521 0.162921)
							(end -0.1524 0.127)
						)
						(arc
							(start -0.1524 -0.127)
							(mid -0.137521 -0.162921)
							(end -0.1016 -0.1778)
						)
						(arc
							(start 0.1016 -0.1778)
							(mid 0.137521 -0.162921)
							(end 0.1524 -0.127)
						)
					)
					(width 0)
					(fill yes)
				)
			)
		)
	)
	(footprint ""
		(layer "B.Cu")
		(at 106.18216 -33.655)
		(property "Reference" "STP27"
			(at 0 0 0)
			(layer "B.SilkS")
			(hide yes)
			(effects
				(font
					(size 1.27 1.27)
				)
				(justify mirror)
			)
		)
		(property "Value" "TPAD28"
			(at -0.0127 -1.8034 0)
			(unlocked yes)
			(layer "B.Fab")
			(hide yes)
			(effects
				(font
					(size 1.016 1.016)
					(thickness 0.1524)
				)
				(justify mirror)
			)
		)
		(property "Device Type" "TPAD28"
			(at -0.0127 -3.3274 0)
			(unlocked yes)
			(layer "B.Fab")
			(hide yes)
			(effects
				(font
					(size 1.016 1.016)
					(thickness 0.1524)
				)
				(justify mirror)
			)
		)
		(duplicate_pad_numbers_are_jumpers no)
		(fp_poly
			(pts
				(arc
					(start 0.3556 0)
					(mid -0.3556 0)
					(end 0.3556 0)
				)
			)
			(stroke
				(width 0)
				(type default)
			)
			(fill no)
			(layer "B.CrtYd")
		)
		(fp_poly
			(pts
				(arc
					(start 0.6096 0)
					(mid -0.6096 0)
					(end 0.6096 0)
				)
			)
			(stroke
				(width 0)
				(type default)
			)
			(fill no)
			(layer "B.Fab")
		)
		(pad "1" smd circle
			(at 0 0 180)
			(size 0.7112 0.7112)
			(layers "B.Cu" "B.Mask" "B.Paste")
			(net "IOC_UART_1_TX")
		)
	)
	(footprint ""
		(layer "B.Cu")
		(at 112.30737 -91.5416 90)
		(property "Reference" "SC1252"
			(at 0 0 90)
			(layer "B.SilkS")
			(hide yes)
			(effects
				(font
					(size 1.27 1.27)
				)
				(justify mirror)
			)
		)
		(property "Value" "SCD1U6D3V1KX-GP"
			(at 2.8321 -1.7399 90)
			(unlocked yes)
			(layer "B.Fab")
			(hide yes)
			(effects
				(font
					(size 1.016 1.016)
					(thickness 0.1524)
				)
				(justify mirror)
			)
		)
		(property "Device Type" "C0201H13"
			(at 2.8321 -3.2639 90)
			(unlocked yes)
			(layer "B.Fab")
			(hide yes)
			(effects
				(font
					(size 1.016 1.016)
					(thickness 0.1524)
				)
				(justify mirror)
			)
		)
		(duplicate_pad_numbers_are_jumpers no)
		(fp_rect
			(start 0.2794 0.6477)
			(end -0.2794 -0.6477)
			(stroke
				(width 0)
				(type default)
			)
			(fill no)
			(layer "B.CrtYd")
		)
		(fp_rect
			(start 0.2794 0.6477)
			(end -0.2794 -0.6477)
			(stroke
				(width 0)
				(type default)
			)
			(fill no)
			(layer "B.Fab")
		)
		(pad "1" smd custom
			(at 0 -0.2794 270)
			(size 0.0762 0.0762)
			(layers "B.Cu" "B.Mask" "B.Paste")
			(net "P0V9_E")
			(options
				(clearance outline)
				(anchor circle)
			)
			(primitives
				(gr_poly
					(pts
						(arc
							(start 0.1524 0.127)
							(mid 0.137521 0.162921)
							(end 0.1016 0.1778)
						)
						(arc
							(start -0.1016 0.1778)
							(mid -0.137521 0.162921)
							(end -0.1524 0.127)
						)
						(arc
							(start -0.1524 -0.127)
							(mid -0.137521 -0.162921)
							(end -0.1016 -0.1778)
						)
						(arc
							(start 0.1016 -0.1778)
							(mid 0.137521 -0.162921)
							(end 0.1524 -0.127)
						)
					)
					(width 0)
					(fill yes)
				)
			)
		)
		(pad "2" smd custom
			(at 0 0.2794 270)
			(size 0.0762 0.0762)
			(layers "B.Cu" "B.Mask" "B.Paste")
			(net "GND")
			(options
				(clearance outline)
				(anchor circle)
			)
			(primitives
				(gr_poly
					(pts
						(arc
							(start 0.1524 0.127)
							(mid 0.137521 0.162921)
							(end 0.1016 0.1778)
						)
						(arc
							(start -0.1016 0.1778)
							(mid -0.137521 0.162921)
							(end -0.1524 0.127)
						)
						(arc
							(start -0.1524 -0.127)
							(mid -0.137521 -0.162921)
							(end -0.1016 -0.1778)
						)
						(arc
							(start 0.1016 -0.1778)
							(mid 0.137521 -0.162921)
							(end 0.1524 -0.127)
						)
					)
					(width 0)
					(fill yes)
				)
			)
		)
	)
	(footprint ""
		(layer "B.Cu")
		(at 16.884904 -100.400866)
		(property "Reference" "C132"
			(at 0 0 0)
			(layer "B.SilkS")
			(hide yes)
			(effects
				(font
					(size 1.27 1.27)
				)
				(justify mirror)
			)
		)
		(property "Value" "SCD01U50V2KX-1GP"
			(at -1.1811 -2.7051 0)
			(unlocked yes)
			(layer "B.Fab")
			(hide yes)
			(effects
				(font
					(size 1.016 1.016)
					(thickness 0.1524)
				)
				(justify mirror)
			)
		)
		(property "Device Type" "C402H22"
			(at -1.1811 -4.2291 0)
			(unlocked yes)
			(layer "B.Fab")
			(hide yes)
			(effects
				(font
					(size 1.016 1.016)
					(thickness 0.1524)
				)
				(justify mirror)
			)
		)
		(duplicate_pad_numbers_are_jumpers no)
		(fp_rect
			(start 0.4318 0.9525)
			(end -0.4318 -0.9525)
			(stroke
				(width 0)
				(type default)
			)
			(fill no)
			(layer "B.CrtYd")
		)
		(fp_rect
			(start 0.4318 0.9525)
			(end -0.4318 -0.9525)
			(stroke
				(width 0)
				(type default)
			)
			(fill no)
			(layer "B.Fab")
		)
		(pad "1" smd custom
			(at 0 -0.4445 180)
			(size 0.1524 0.1524)
			(layers "B.Cu" "B.Mask" "B.Paste")
			(net "IOC_SAS_RX_N6")
			(options
				(clearance outline)
				(anchor circle)
			)
			(primitives
				(gr_poly
					(pts
						(arc
							(start 0.3048 0.2032)
							(mid 0.275042 0.275042)
							(end 0.2032 0.3048)
						)
						(arc
							(start -0.2032 0.3048)
							(mid -0.275042 0.275042)
							(end -0.3048 0.2032)
						)
						(arc
							(start -0.3048 -0.2032)
							(mid -0.275042 -0.275042)
							(end -0.2032 -0.3048)
						)
						(arc
							(start 0.2032 -0.3048)
							(mid 0.275042 -0.275042)
							(end 0.3048 -0.2032)
						)
					)
					(width 0)
					(fill yes)
				)
			)
		)
		(pad "2" smd custom
			(at 0 0.4445 180)
			(size 0.1524 0.1524)
			(layers "B.Cu" "B.Mask" "B.Paste")
			(net "SAS_EXT_CONN_RX18_N")
			(options
				(clearance outline)
				(anchor circle)
			)
			(primitives
				(gr_poly
					(pts
						(arc
							(start 0.3048 0.2032)
							(mid 0.275042 0.275042)
							(end 0.2032 0.3048)
						)
						(arc
							(start -0.2032 0.3048)
							(mid -0.275042 0.275042)
							(end -0.3048 0.2032)
						)
						(arc
							(start -0.3048 -0.2032)
							(mid -0.275042 -0.275042)
							(end -0.2032 -0.3048)
						)
						(arc
							(start 0.2032 -0.3048)
							(mid 0.275042 -0.275042)
							(end 0.3048 -0.2032)
						)
					)
					(width 0)
					(fill yes)
				)
			)
		)
	)
	(footprint ""
		(layer "B.Cu")
		(at 126.63297 -96.52 90)
		(property "Reference" "SC1161"
			(at 0 0 90)
			(layer "B.SilkS")
			(hide yes)
			(effects
				(font
					(size 1.27 1.27)
				)
				(justify mirror)
			)
		)
		(property "Value" "SCD1U6D3V1KX-GP"
			(at 2.8321 -1.7399 90)
			(unlocked yes)
			(layer "B.Fab")
			(hide yes)
			(effects
				(font
					(size 1.016 1.016)
					(thickness 0.1524)
				)
				(justify mirror)
			)
		)
		(property "Device Type" "C0201H13"
			(at 2.8321 -3.2639 90)
			(unlocked yes)
			(layer "B.Fab")
			(hide yes)
			(effects
				(font
					(size 1.016 1.016)
					(thickness 0.1524)
				)
				(justify mirror)
			)
		)
		(duplicate_pad_numbers_are_jumpers no)
		(fp_rect
			(start 0.2794 0.6477)
			(end -0.2794 -0.6477)
			(stroke
				(width 0)
				(type default)
			)
			(fill no)
			(layer "B.CrtYd")
		)
		(fp_rect
			(start 0.2794 0.6477)
			(end -0.2794 -0.6477)
			(stroke
				(width 0)
				(type default)
			)
			(fill no)
			(layer "B.Fab")
		)
		(pad "1" smd custom
			(at 0 -0.2794 270)
			(size 0.0762 0.0762)
			(layers "B.Cu" "B.Mask" "B.Paste")
			(net "GB_VDDA")
			(options
				(clearance outline)
				(anchor circle)
			)
			(primitives
				(gr_poly
					(pts
						(arc
							(start 0.1524 0.127)
							(mid 0.137521 0.162921)
							(end 0.1016 0.1778)
						)
						(arc
							(start -0.1016 0.1778)
							(mid -0.137521 0.162921)
							(end -0.1524 0.127)
						)
						(arc
							(start -0.1524 -0.127)
							(mid -0.137521 -0.162921)
							(end -0.1016 -0.1778)
						)
						(arc
							(start 0.1016 -0.1778)
							(mid 0.137521 -0.162921)
							(end 0.1524 -0.127)
						)
					)
					(width 0)
					(fill yes)
				)
			)
		)
		(pad "2" smd custom
			(at 0 0.2794 270)
			(size 0.0762 0.0762)
			(layers "B.Cu" "B.Mask" "B.Paste")
			(net "GND")
			(options
				(clearance outline)
				(anchor circle)
			)
			(primitives
				(gr_poly
					(pts
						(arc
							(start 0.1524 0.127)
							(mid 0.137521 0.162921)
							(end 0.1016 0.1778)
						)
						(arc
							(start -0.1016 0.1778)
							(mid -0.137521 0.162921)
							(end -0.1524 0.127)
						)
						(arc
							(start -0.1524 -0.127)
							(mid -0.137521 -0.162921)
							(end -0.1016 -0.1778)
						)
						(arc
							(start 0.1016 -0.1778)
							(mid 0.137521 -0.162921)
							(end 0.1524 -0.127)
						)
					)
					(width 0)
					(fill yes)
				)
			)
		)
	)
	(footprint ""
		(layer "B.Cu")
		(at 94.342966 -52.197)
		(property "Reference" "SR673"
			(at 0 0 0)
			(layer "B.SilkS")
			(hide yes)
			(effects
				(font
					(size 1.27 1.27)
				)
				(justify mirror)
			)
		)
		(property "Value" "4K7R2F-GP"
			(at -0.064008 -3.993896 0)
			(unlocked yes)
			(layer "B.Fab")
			(hide yes)
			(effects
				(font
					(size 1.016 1.016)
					(thickness 0.1524)
				)
				(justify mirror)
			)
		)
		(property "Device Type" "R402H16"
			(at -0.064008 -5.517896 0)
			(unlocked yes)
			(layer "B.Fab")
			(hide yes)
			(effects
				(font
					(size 1.016 1.016)
					(thickness 0.1524)
				)
				(justify mirror)
			)
		)
		(duplicate_pad_numbers_are_jumpers no)
		(fp_line
			(start -0.508 -0.9398)
			(end 0.508 -0.9398)
			(stroke
				(width 0.1524)
				(type default)
			)
			(layer "B.SilkS")
		)
		(fp_line
			(start 0.508 -0.9398)
			(end 0.508 0.9398)
			(stroke
				(width 0.1524)
				(type default)
			)
			(layer "B.SilkS")
		)
		(fp_rect
			(start 0.508 0.9398)
			(end -0.508 -0.9398)
			(stroke
				(width 0)
				(type default)
			)
			(fill no)
			(layer "B.CrtYd")
		)
		(fp_rect
			(start 0.508 0.9398)
			(end -0.508 -0.9398)
			(stroke
				(width 0)
				(type default)
			)
			(fill no)
			(layer "B.Fab")
		)
		(pad "1" smd custom
			(at 0 -0.4445 180)
			(size 0.1397 0.1397)
			(layers "B.Cu" "B.Mask" "B.Paste")
			(net "P1V8_C")
			(options
				(clearance outline)
				(anchor circle)
			)
			(primitives
				(gr_poly
					(pts
						(arc
							(start -0.1778 0.2794)
							(mid -0.249642 0.249642)
							(end -0.2794 0.1778)
						)
						(arc
							(start -0.2794 -0.1778)
							(mid -0.249642 -0.249642)
							(end -0.1778 -0.2794)
						)
						(arc
							(start 0.1778 -0.2794)
							(mid 0.249642 -0.249642)
							(end 0.2794 -0.1778)
						)
						(arc
							(start 0.2794 0.1778)
							(mid 0.249642 0.249642)
							(end 0.1778 0.2794)
						)
					)
					(width 0)
					(fill yes)
				)
			)
		)
		(pad "2" smd custom
			(at 0 0.4445 180)
			(size 0.1397 0.1397)
			(layers "B.Cu" "B.Mask" "B.Paste")
			(net "ICE1_TDI")
			(options
				(clearance outline)
				(anchor circle)
			)
			(primitives
				(gr_poly
					(pts
						(arc
							(start -0.1778 0.2794)
							(mid -0.249642 0.249642)
							(end -0.2794 0.1778)
						)
						(arc
							(start -0.2794 -0.1778)
							(mid -0.249642 -0.249642)
							(end -0.1778 -0.2794)
						)
						(arc
							(start 0.1778 -0.2794)
							(mid 0.249642 -0.249642)
							(end 0.2794 -0.1778)
						)
						(arc
							(start 0.2794 0.1778)
							(mid 0.249642 0.249642)
							(end 0.1778 0.2794)
						)
					)
					(width 0)
					(fill yes)
				)
			)
		)
	)
)
